# T6G (Grand Teton) — schematic netlist excerpt (pin names and nets, part order shuffled) for the footprints in the layout excerpt that follows; sources: Cadence DE-HDL packaged netlist, KiCad conversion of 04192023_DAF0TMB3IC0_F0TG_MB_C_brd_V02_OCP.brd

R6286  Q_RES  0 5% CHIP  pkg 0402LF  page 178 : A = USB_HUB2_MRP_VBUS_DET ; B = USB_HUB2_TI_PWRCTL_POL_MRP_VBUS_DET
PR3789  Q_RES  25.5K 1% CHIP  pkg 0402LF  page 134 : A = P3V3_AUX ; B = P3V3_OCP_UV_1

(kicad_pcb
	(version 20260206)
	(generator "pcbnew")
	(generator_version "10.0")
	(general
		(thickness 1.6)
		(legacy_teardrops no)
	)
	(paper "A4")
	(title_block
		(title "04192023_DAF0TMB3IC0_F0TG_MB_C_brd_V02_OCP.brd")
		(comment 1 "Grand Teton / footprints 3328-3329 of 8354")
	)
	(layers
		(0 "F.Cu" signal "TOP")
		(4 "In1.Cu" signal "GND")
		(6 "In2.Cu" signal "IN1")
		(8 "In3.Cu" signal "GND1")
		(10 "In4.Cu" signal "IN2")
		(12 "In5.Cu" signal "GND2")
		(14 "In6.Cu" signal "IN3")
		(16 "In7.Cu" signal "GND3")
		(18 "In8.Cu" signal "VCC")
		(20 "In9.Cu" signal "VCC1")
		(22 "In10.Cu" signal "GND4")
		(24 "In11.Cu" signal "IN4")
		(26 "In12.Cu" signal "GND5")
		(28 "In13.Cu" signal "IN5")
		(30 "In14.Cu" signal "GND6")
		(32 "In15.Cu" signal "IN6")
		(34 "In16.Cu" signal "GND7")
		(2 "B.Cu" signal "BOTTOM")
		(9 "F.Adhes" user "F.Adhesive")
		(11 "B.Adhes" user "B.Adhesive")
		(13 "F.Paste" user "Package Geometry/Pastemask Top")
		(15 "B.Paste" user "Package Geometry/Pastemask Bottom")
		(5 "F.SilkS" user "Ref Des/Silkscreen Top")
		(7 "B.SilkS" user "Ref Des/Silkscreen Bottom")
		(1 "F.Mask" user "Board Geometry/Soldermask Top")
		(3 "B.Mask" user "Board Geometry/Soldermask Bottom")
		(17 "Dwgs.User" user "User.Drawings")
		(19 "Cmts.User" user "User.Comments")
		(21 "Eco1.User" user "User.Eco1")
		(23 "Eco2.User" user "User.Eco2")
		(25 "Edge.Cuts" user "Board Geometry/Outline")
		(27 "Margin" user)
		(31 "F.CrtYd" user "Package Geometry/Place Bound Top")
		(29 "B.CrtYd" user "Package Geometry/Place Bound Bottom")
		(35 "F.Fab" user "Ref Des/Assembly Top")
		(33 "B.Fab" user "Ref Des/Assembly Bottom")
	)
	(footprint ""
		(layer "F.Cu")
		(at 114.299238 -39.40175 -90)
		(property "Reference" "R6286"
			(at 0 0 270)
			(layer "F.SilkS")
			(hide yes)
			(effects
				(font
					(size 1.27 1.27)
				)
			)
		)
		(property "Value" ""
			(at 0 0 270)
			(layer "F.Fab")
			(effects
				(font
					(size 1.27 1.27)
				)
			)
		)
		(duplicate_pad_numbers_are_jumpers no)
		(fp_line
			(start -0.7874 0.4064)
			(end -0.7874 -0.4064)
			(stroke
				(width 0.1524)
				(type default)
			)
			(layer "F.SilkS")
		)
		(fp_line
			(start 0.7874 0.4064)
			(end -0.7874 0.4064)
			(stroke
				(width 0.1524)
				(type default)
			)
			(layer "F.SilkS")
		)
		(fp_line
			(start -0.7874 -0.4064)
			(end 0.7874 -0.4064)
			(stroke
				(width 0.1524)
				(type default)
			)
			(layer "F.SilkS")
		)
		(fp_line
			(start 0.7874 -0.4064)
			(end 0.7874 0.4064)
			(stroke
				(width 0.1524)
				(type default)
			)
			(layer "F.SilkS")
		)
		(fp_line
			(start -0.67945 0.3048)
			(end -0.67945 -0.305054)
			(stroke
				(width 0.1)
				(type default)
			)
			(layer "F.Fab")
		)
		(fp_line
			(start -0.12065 0.3048)
			(end -0.67945 0.3048)
			(stroke
				(width 0.1)
				(type default)
			)
			(layer "F.Fab")
		)
		(fp_line
			(start 0.120396 0.3048)
			(end 0.120396 0.2794)
			(stroke
				(width 0.1)
				(type default)
			)
			(layer "F.Fab")
		)
		(fp_line
			(start 0.67945 0.3048)
			(end 0.120396 0.3048)
			(stroke
				(width 0.1)
				(type default)
			)
			(layer "F.Fab")
		)
		(fp_line
			(start -0.12065 0.2794)
			(end -0.12065 0.3048)
			(stroke
				(width 0.1)
				(type default)
			)
			(layer "F.Fab")
		)
		(fp_line
			(start 0.120396 0.2794)
			(end -0.12065 0.2794)
			(stroke
				(width 0.1)
				(type default)
			)
			(layer "F.Fab")
		)
		(fp_line
			(start -0.12065 -0.2794)
			(end 0.12065 -0.2794)
			(stroke
				(width 0.1)
				(type default)
			)
			(layer "F.Fab")
		)
		(fp_line
			(start 0.12065 -0.2794)
			(end 0.12065 -0.3048)
			(stroke
				(width 0.1)
				(type default)
			)
			(layer "F.Fab")
		)
		(fp_line
			(start 0.12065 -0.3048)
			(end 0.67945 -0.3048)
			(stroke
				(width 0.1)
				(type default)
			)
			(layer "F.Fab")
		)
		(fp_line
			(start 0.67945 -0.3048)
			(end 0.67945 0.3048)
			(stroke
				(width 0.1)
				(type default)
			)
			(layer "F.Fab")
		)
		(fp_line
			(start -0.67945 -0.305054)
			(end -0.12065 -0.305054)
			(stroke
				(width 0.1)
				(type default)
			)
			(layer "F.Fab")
		)
		(fp_line
			(start -0.12065 -0.305054)
			(end -0.12065 -0.2794)
			(stroke
				(width 0.1)
				(type default)
			)
			(layer "F.Fab")
		)
		(pad "1" smd circle
			(at -0.40005 0 270)
			(size 0 0)
			(layers "F.Cu" "F.Mask" "F.Paste")
			(net "USB_HUB2_MRP_VBUS_DET")
		)
		(pad "2" smd circle
			(at 0.40005 0 270)
			(size 0 0)
			(layers "F.Cu" "F.Mask" "F.Paste")
			(net "USB_HUB2_TI_PWRCTL_POL_MRP_VBUS_DET")
		)
	)
	(footprint ""
		(layer "F.Cu")
		(at 429.299116 -109.26699 -90)
		(property "Reference" "PR3789"
			(at 0 0 270)
			(layer "F.SilkS")
			(hide yes)
			(effects
				(font
					(size 1.27 1.27)
				)
			)
		)
		(property "Value" ""
			(at 0 0 270)
			(layer "F.Fab")
			(effects
				(font
					(size 1.27 1.27)
				)
			)
		)
		(duplicate_pad_numbers_are_jumpers no)
		(fp_line
			(start -0.7874 0.4064)
			(end -0.7874 -0.4064)
			(stroke
				(width 0.1524)
				(type default)
			)
			(layer "F.SilkS")
		)
		(fp_line
			(start 0.7874 0.4064)
			(end -0.7874 0.4064)
			(stroke
				(width 0.1524)
				(type default)
			)
			(layer "F.SilkS")
		)
		(fp_line
			(start -0.7874 -0.4064)
			(end 0.7874 -0.4064)
			(stroke
				(width 0.1524)
				(type default)
			)
			(layer "F.SilkS")
		)
		(fp_line
			(start 0.7874 -0.4064)
			(end 0.7874 0.4064)
			(stroke
				(width 0.1524)
				(type default)
			)
			(layer "F.SilkS")
		)
		(fp_line
			(start -0.67945 0.3048)
			(end -0.67945 -0.305054)
			(stroke
				(width 0.1)
				(type default)
			)
			(layer "F.Fab")
		)
		(fp_line
			(start -0.12065 0.3048)
			(end -0.67945 0.3048)
			(stroke
				(width 0.1)
				(type default)
			)
			(layer "F.Fab")
		)
		(fp_line
			(start 0.120396 0.3048)
			(end 0.120396 0.2794)
			(stroke
				(width 0.1)
				(type default)
			)
			(layer "F.Fab")
		)
		(fp_line
			(start 0.67945 0.3048)
			(end 0.120396 0.3048)
			(stroke
				(width 0.1)
				(type default)
			)
			(layer "F.Fab")
		)
		(fp_line
			(start -0.12065 0.2794)
			(end -0.12065 0.3048)
			(stroke
				(width 0.1)
				(type default)
			)
			(layer "F.Fab")
		)
		(fp_line
			(start 0.120396 0.2794)
			(end -0.12065 0.2794)
			(stroke
				(width 0.1)
				(type default)
			)
			(layer "F.Fab")
		)
		(fp_line
			(start -0.12065 -0.2794)
			(end 0.12065 -0.2794)
			(stroke
				(width 0.1)
				(type default)
			)
			(layer "F.Fab")
		)
		(fp_line
			(start 0.12065 -0.2794)
			(end 0.12065 -0.3048)
			(stroke
				(width 0.1)
				(type default)
			)
			(layer "F.Fab")
		)
		(fp_line
			(start 0.12065 -0.3048)
			(end 0.67945 -0.3048)
			(stroke
				(width 0.1)
				(type default)
			)
			(layer "F.Fab")
		)
		(fp_line
			(start 0.67945 -0.3048)
			(end 0.67945 0.3048)
			(stroke
				(width 0.1)
				(type default)
			)
			(layer "F.Fab")
		)
		(fp_line
			(start -0.67945 -0.305054)
			(end -0.12065 -0.305054)
			(stroke
				(width 0.1)
				(type default)
			)
			(layer "F.Fab")
		)
		(fp_line
			(start -0.12065 -0.305054)
			(end -0.12065 -0.2794)
			(stroke
				(width 0.1)
				(type default)
			)
			(layer "F.Fab")
		)
		(pad "1" smd circle
			(at -0.40005 0 270)
			(size 0 0)
			(layers "F.Cu" "F.Mask" "F.Paste")
			(net "P3V3_AUX")
		)
		(pad "2" smd circle
			(at 0.40005 0 270)
			(size 0 0)
			(layers "F.Cu" "F.Mask" "F.Paste")
			(net "P3V3_OCP_UV_1")
		)
	)
)
